(kicad_pcb
	(version 20260206)
	(generator "pcbnew")
	(generator_version "10.0")
	(general
		(thickness 1.6)
		(legacy_teardrops no)
	)
	(paper "A4")
	(title_block
		(title "Bryce Canyon_IOM_M2_16342-2_OCP.brd")
		(comment 1 "Bryce Canyon / footprints 769-776 of 1146")
	)
	(layers
		(0 "F.Cu" signal "TOP")
		(4 "In1.Cu" signal "L2GND")
		(6 "In2.Cu" signal "L3")
		(8 "In3.Cu" signal "L4VCC")
		(10 "In4.Cu" signal "L5VCC")
		(12 "In5.Cu" signal "L6")
		(14 "In6.Cu" signal "L7GND")
		(2 "B.Cu" signal "BOTTOM")
		(9 "F.Adhes" user "F.Adhesive")
		(11 "B.Adhes" user "B.Adhesive")
		(13 "F.Paste" user "Package Geometry/Pastemask Top")
		(15 "B.Paste" user "Package Geometry/Pastemask Bottom")
		(5 "F.SilkS" user "Ref Des/Silkscreen Top")
		(7 "B.SilkS" user "Ref Des/Silkscreen Bottom")
		(1 "F.Mask" user "Board Geometry/Soldermask Top")
		(3 "B.Mask" user "Board Geometry/Soldermask Bottom")
		(17 "Dwgs.User" user "User.Drawings")
		(19 "Cmts.User" user "User.Comments")
		(21 "Eco1.User" user "User.Eco1")
		(23 "Eco2.User" user "User.Eco2")
		(25 "Edge.Cuts" user "Board Geometry/Outline")
		(27 "Margin" user)
		(31 "F.CrtYd" user "Package Geometry/Place Bound Top")
		(29 "B.CrtYd" user "Package Geometry/Place Bound Bottom")
		(35 "F.Fab" user "Ref Des/Assembly Top")
		(33 "B.Fab" user "Ref Des/Assembly Bottom")
	)
	(footprint ""
		(layer "B.Cu")
		(at 226.600004 -51.137566 90)
		(property "Reference" "C153"
			(at 0 0 90)
			(layer "B.SilkS")
			(hide yes)
			(effects
				(font
					(size 1.27 1.27)
				)
				(justify mirror)
			)
		)
		(property "Value" "SC10U16V5KX-7-GP-U"
			(at 0.0762 -6.1214 90)
			(unlocked yes)
			(layer "B.Fab")
			(hide yes)
			(effects
				(font
					(size 1.016 1.016)
					(thickness 0.1524)
				)
				(justify mirror)
			)
		)
		(property "Device Type" "C805H58"
			(at 0.0762 -8.1534 90)
			(unlocked yes)
			(layer "B.Fab")
			(hide yes)
			(effects
				(font
					(size 1.016 1.016)
					(thickness 0.1524)
				)
				(justify mirror)
			)
		)
		(duplicate_pad_numbers_are_jumpers no)
		(fp_line
			(start -0.635 0)
			(end 0.635 0)
			(stroke
				(width 0.508)
				(type default)
			)
			(layer "B.SilkS")
		)
		(fp_rect
			(start 0.9652 1.778)
			(end -0.9652 -1.778)
			(stroke
				(width 0)
				(type default)
			)
			(fill no)
			(layer "B.CrtYd")
		)
		(fp_poly
			(pts
				(xy 0.9652 -1.778) (xy -0.9652 -1.778) (xy -0.9652 1.778) (xy 0.9652 1.778)
			)
			(stroke
				(width 0)
				(type default)
			)
			(fill no)
			(layer "B.Fab")
		)
		(pad "1" smd rect
			(at 0 -0.9652 270)
			(size 1.397 1.143)
			(layers "B.Cu" "B.Mask" "B.Paste")
			(net "P12V_STBY_VIN_PU1")
		)
		(pad "2" smd rect
			(at 0 0.9652 270)
			(size 1.397 1.143)
			(layers "B.Cu" "B.Mask" "B.Paste")
			(net "GND")
		)
	)
	(footprint ""
		(layer "B.Cu")
		(at 113.386362 -8.8138)
		(property "Reference" "C150"
			(at 0 0 0)
			(layer "B.SilkS")
			(hide yes)
			(effects
				(font
					(size 1.27 1.27)
				)
				(justify mirror)
			)
		)
		(property "Value" "SCD1U50V3KX-GP"
			(at 0 -2.8194 0)
			(unlocked yes)
			(layer "B.Fab")
			(hide yes)
			(effects
				(font
					(size 1.016 1.016)
					(thickness 0.1524)
				)
				(justify mirror)
			)
		)
		(property "Device Type" "C603H36"
			(at 0 -4.3434 0)
			(unlocked yes)
			(layer "B.Fab")
			(hide yes)
			(effects
				(font
					(size 1.016 1.016)
					(thickness 0.1524)
				)
				(justify mirror)
			)
		)
		(duplicate_pad_numbers_are_jumpers no)
		(fp_line
			(start -0.508 0)
			(end 0.508 0)
			(stroke
				(width 0.2032)
				(type default)
			)
			(layer "B.SilkS")
		)
		(fp_rect
			(start 0.5842 1.3335)
			(end -0.5842 -1.3335)
			(stroke
				(width 0)
				(type default)
			)
			(fill no)
			(layer "B.CrtYd")
		)
		(fp_rect
			(start 0.5842 1.3335)
			(end -0.5842 -1.3335)
			(stroke
				(width 0)
				(type default)
			)
			(fill no)
			(layer "B.Fab")
		)
		(pad "1" smd custom
			(at 0 -0.762 180)
			(size 0.2159 0.2159)
			(layers "B.Cu" "B.Mask" "B.Paste")
			(net "MB0_ISTART_R")
			(options
				(clearance outline)
				(anchor circle)
			)
			(primitives
				(gr_poly
					(pts
						(arc
							(start -0.3302 0.4318)
							(mid -0.402042 0.402042)
							(end -0.4318 0.3302)
						)
						(arc
							(start -0.4318 -0.3302)
							(mid -0.402042 -0.402042)
							(end -0.3302 -0.4318)
						)
						(arc
							(start 0.3302 -0.4318)
							(mid 0.402042 -0.402042)
							(end 0.4318 -0.3302)
						)
						(arc
							(start 0.4318 0.3302)
							(mid 0.402042 0.402042)
							(end 0.3302 0.4318)
						)
					)
					(width 0)
					(fill yes)
				)
			)
		)
		(pad "2" smd custom
			(at 0 0.762 180)
			(size 0.2159 0.2159)
			(layers "B.Cu" "B.Mask" "B.Paste")
			(net "AGND_CURRENT_MON")
			(options
				(clearance outline)
				(anchor circle)
			)
			(primitives
				(gr_poly
					(pts
						(arc
							(start -0.3302 0.4318)
							(mid -0.402042 0.402042)
							(end -0.4318 0.3302)
						)
						(arc
							(start -0.4318 -0.3302)
							(mid -0.402042 -0.402042)
							(end -0.3302 -0.4318)
						)
						(arc
							(start 0.3302 -0.4318)
							(mid 0.402042 -0.402042)
							(end 0.4318 -0.3302)
						)
						(arc
							(start 0.4318 0.3302)
							(mid 0.402042 0.402042)
							(end 0.3302 0.4318)
						)
					)
					(width 0)
					(fill yes)
				)
			)
		)
	)
	(footprint ""
		(layer "B.Cu")
		(at 49.911 -154.8384 180)
		(property "Reference" "R298"
			(at 0 0 0)
			(layer "B.SilkS")
			(hide yes)
			(effects
				(font
					(size 1.27 1.27)
				)
				(justify mirror)
			)
		)
		(property "Value" "0R2J-2-GP"
			(at -0.064008 -3.993896 180)
			(unlocked yes)
			(layer "B.Fab")
			(hide yes)
			(effects
				(font
					(size 1.016 1.016)
					(thickness 0.1524)
				)
				(justify mirror)
			)
		)
		(property "Device Type" "R402H16"
			(at -0.064008 -5.517896 180)
			(unlocked yes)
			(layer "B.Fab")
			(hide yes)
			(effects
				(font
					(size 1.016 1.016)
					(thickness 0.1524)
				)
				(justify mirror)
			)
		)
		(duplicate_pad_numbers_are_jumpers no)
		(fp_line
			(start 0.508 -0.9398)
			(end 0.508 0.9398)
			(stroke
				(width 0.1524)
				(type default)
			)
			(layer "B.SilkS")
		)
		(fp_line
			(start -0.508 -0.9398)
			(end 0.508 -0.9398)
			(stroke
				(width 0.1524)
				(type default)
			)
			(layer "B.SilkS")
		)
		(fp_rect
			(start 0.508 0.9398)
			(end -0.508 -0.9398)
			(stroke
				(width 0)
				(type default)
			)
			(fill no)
			(layer "B.CrtYd")
		)
		(fp_rect
			(start 0.508 0.9398)
			(end -0.508 -0.9398)
			(stroke
				(width 0)
				(type default)
			)
			(fill no)
			(layer "B.Fab")
		)
		(pad "1" smd custom
			(at 0 -0.4445)
			(size 0.1397 0.1397)
			(layers "B.Cu" "B.Mask" "B.Paste")
			(net "UART_BMC_R_RX")
			(options
				(clearance outline)
				(anchor circle)
			)
			(primitives
				(gr_poly
					(pts
						(arc
							(start -0.1778 0.2794)
							(mid -0.249642 0.249642)
							(end -0.2794 0.1778)
						)
						(arc
							(start -0.2794 -0.1778)
							(mid -0.249642 -0.249642)
							(end -0.1778 -0.2794)
						)
						(arc
							(start 0.1778 -0.2794)
							(mid 0.249642 -0.249642)
							(end 0.2794 -0.1778)
						)
						(arc
							(start 0.2794 0.1778)
							(mid 0.249642 0.249642)
							(end 0.1778 0.2794)
						)
					)
					(width 0)
					(fill yes)
				)
			)
		)
		(pad "2" smd custom
			(at 0 0.4445)
			(size 0.1397 0.1397)
			(layers "B.Cu" "B.Mask" "B.Paste")
			(net "UART_BMC_RX")
			(options
				(clearance outline)
				(anchor circle)
			)
			(primitives
				(gr_poly
					(pts
						(arc
							(start -0.1778 0.2794)
							(mid -0.249642 0.249642)
							(end -0.2794 0.1778)
						)
						(arc
							(start -0.2794 -0.1778)
							(mid -0.249642 -0.249642)
							(end -0.1778 -0.2794)
						)
						(arc
							(start 0.1778 -0.2794)
							(mid 0.249642 -0.249642)
							(end 0.2794 -0.1778)
						)
						(arc
							(start 0.2794 0.1778)
							(mid 0.249642 0.249642)
							(end 0.1778 0.2794)
						)
					)
					(width 0)
					(fill yes)
				)
			)
		)
	)
	(footprint ""
		(layer "B.Cu")
		(at 219.277692 -88.57361 90)
		(property "Reference" "C653"
			(at 0 0 90)
			(layer "B.SilkS")
			(hide yes)
			(effects
				(font
					(size 1.27 1.27)
				)
				(justify mirror)
			)
		)
		(property "Value" "SCD1U16V2KX-3GP"
			(at -1.1811 -2.7051 90)
			(unlocked yes)
			(layer "B.Fab")
			(hide yes)
			(effects
				(font
					(size 1.016 1.016)
					(thickness 0.1524)
				)
				(justify mirror)
			)
		)
		(property "Device Type" "C402H22"
			(at -1.1811 -4.2291 90)
			(unlocked yes)
			(layer "B.Fab")
			(hide yes)
			(effects
				(font
					(size 1.016 1.016)
					(thickness 0.1524)
				)
				(justify mirror)
			)
		)
		(duplicate_pad_numbers_are_jumpers no)
		(fp_rect
			(start 0.4318 0.9525)
			(end -0.4318 -0.9525)
			(stroke
				(width 0)
				(type default)
			)
			(fill no)
			(layer "B.CrtYd")
		)
		(fp_rect
			(start 0.4318 0.9525)
			(end -0.4318 -0.9525)
			(stroke
				(width 0)
				(type default)
			)
			(fill no)
			(layer "B.Fab")
		)
		(pad "1" smd custom
			(at 0 -0.4445 270)
			(size 0.1524 0.1524)
			(layers "B.Cu" "B.Mask" "B.Paste")
			(net "P3V3_M2_VBST_RC")
			(options
				(clearance outline)
				(anchor circle)
			)
			(primitives
				(gr_poly
					(pts
						(arc
							(start 0.3048 0.2032)
							(mid 0.275042 0.275042)
							(end 0.2032 0.3048)
						)
						(arc
							(start -0.2032 0.3048)
							(mid -0.275042 0.275042)
							(end -0.3048 0.2032)
						)
						(arc
							(start -0.3048 -0.2032)
							(mid -0.275042 -0.275042)
							(end -0.2032 -0.3048)
						)
						(arc
							(start 0.2032 -0.3048)
							(mid 0.275042 -0.275042)
							(end 0.3048 -0.2032)
						)
					)
					(width 0)
					(fill yes)
				)
			)
		)
		(pad "2" smd custom
			(at 0 0.4445 270)
			(size 0.1524 0.1524)
			(layers "B.Cu" "B.Mask" "B.Paste")
			(net "P3V3_M2_LL")
			(options
				(clearance outline)
				(anchor circle)
			)
			(primitives
				(gr_poly
					(pts
						(arc
							(start 0.3048 0.2032)
							(mid 0.275042 0.275042)
							(end 0.2032 0.3048)
						)
						(arc
							(start -0.2032 0.3048)
							(mid -0.275042 0.275042)
							(end -0.3048 0.2032)
						)
						(arc
							(start -0.3048 -0.2032)
							(mid -0.275042 -0.275042)
							(end -0.2032 -0.3048)
						)
						(arc
							(start 0.2032 -0.3048)
							(mid 0.275042 -0.275042)
							(end 0.3048 -0.2032)
						)
					)
					(width 0)
					(fill yes)
				)
			)
		)
	)
	(footprint ""
		(layer "B.Cu")
		(at 43.129454 -120.210072 -90)
		(property "Reference" "R344"
			(at 0 0 90)
			(layer "B.SilkS")
			(hide yes)
			(effects
				(font
					(size 1.27 1.27)
				)
				(justify mirror)
			)
		)
		(property "Value" "0R2J-2-GP"
			(at -0.064008 -3.993896 270)
			(unlocked yes)
			(layer "B.Fab")
			(hide yes)
			(effects
				(font
					(size 1.016 1.016)
					(thickness 0.1524)
				)
				(justify mirror)
			)
		)
		(property "Device Type" "R402H16"
			(at -0.064008 -5.517896 270)
			(unlocked yes)
			(layer "B.Fab")
			(hide yes)
			(effects
				(font
					(size 1.016 1.016)
					(thickness 0.1524)
				)
				(justify mirror)
			)
		)
		(duplicate_pad_numbers_are_jumpers no)
		(fp_line
			(start -0.508 -0.9398)
			(end 0.508 -0.9398)
			(stroke
				(width 0.1524)
				(type default)
			)
			(layer "B.SilkS")
		)
		(fp_line
			(start 0.508 -0.9398)
			(end 0.508 0.9398)
			(stroke
				(width 0.1524)
				(type default)
			)
			(layer "B.SilkS")
		)
		(fp_rect
			(start 0.508 0.9398)
			(end -0.508 -0.9398)
			(stroke
				(width 0)
				(type default)
			)
			(fill no)
			(layer "B.CrtYd")
		)
		(fp_rect
			(start 0.508 0.9398)
			(end -0.508 -0.9398)
			(stroke
				(width 0)
				(type default)
			)
			(fill no)
			(layer "B.Fab")
		)
		(pad "1" smd custom
			(at 0 -0.4445 90)
			(size 0.1397 0.1397)
			(layers "B.Cu" "B.Mask" "B.Paste")
			(net "TEMP_3_SCL")
			(options
				(clearance outline)
				(anchor circle)
			)
			(primitives
				(gr_poly
					(pts
						(arc
							(start -0.1778 0.2794)
							(mid -0.249642 0.249642)
							(end -0.2794 0.1778)
						)
						(arc
							(start -0.2794 -0.1778)
							(mid -0.249642 -0.249642)
							(end -0.1778 -0.2794)
						)
						(arc
							(start 0.1778 -0.2794)
							(mid 0.249642 -0.249642)
							(end 0.2794 -0.1778)
						)
						(arc
							(start 0.2794 0.1778)
							(mid 0.249642 0.249642)
							(end 0.1778 0.2794)
						)
					)
					(width 0)
					(fill yes)
				)
			)
		)
		(pad "2" smd custom
			(at 0 0.4445 90)
			(size 0.1397 0.1397)
			(layers "B.Cu" "B.Mask" "B.Paste")
			(net "I2C_IOM_SCL")
			(options
				(clearance outline)
				(anchor circle)
			)
			(primitives
				(gr_poly
					(pts
						(arc
							(start -0.1778 0.2794)
							(mid -0.249642 0.249642)
							(end -0.2794 0.1778)
						)
						(arc
							(start -0.2794 -0.1778)
							(mid -0.249642 -0.249642)
							(end -0.1778 -0.2794)
						)
						(arc
							(start 0.1778 -0.2794)
							(mid 0.249642 -0.249642)
							(end 0.2794 -0.1778)
						)
						(arc
							(start 0.2794 0.1778)
							(mid 0.249642 0.249642)
							(end 0.1778 0.2794)
						)
					)
					(width 0)
					(fill yes)
				)
			)
		)
	)
	(footprint ""
		(layer "B.Cu")
		(at 224.056956 -101.165152 -90)
		(property "Reference" "C635"
			(at 0 0 90)
			(layer "B.SilkS")
			(hide yes)
			(effects
				(font
					(size 1.27 1.27)
				)
				(justify mirror)
			)
		)
		(property "Value" "SC10U16V5KX-7-GP-U"
			(at 0.0762 -6.1214 270)
			(unlocked yes)
			(layer "B.Fab")
			(hide yes)
			(effects
				(font
					(size 1.016 1.016)
					(thickness 0.1524)
				)
				(justify mirror)
			)
		)
		(property "Device Type" "C805H58"
			(at 0.0762 -8.1534 270)
			(unlocked yes)
			(layer "B.Fab")
			(hide yes)
			(effects
				(font
					(size 1.016 1.016)
					(thickness 0.1524)
				)
				(justify mirror)
			)
		)
		(duplicate_pad_numbers_are_jumpers no)
		(fp_line
			(start -0.635 0)
			(end 0.635 0)
			(stroke
				(width 0.508)
				(type default)
			)
			(layer "B.SilkS")
		)
		(fp_rect
			(start 0.9652 1.778)
			(end -0.9652 -1.778)
			(stroke
				(width 0)
				(type default)
			)
			(fill no)
			(layer "B.CrtYd")
		)
		(fp_poly
			(pts
				(xy 0.9652 -1.778) (xy -0.9652 -1.778) (xy -0.9652 1.778) (xy 0.9652 1.778)
			)
			(stroke
				(width 0)
				(type default)
			)
			(fill no)
			(layer "B.Fab")
		)
		(pad "1" smd rect
			(at 0 -0.9652 90)
			(size 1.397 1.143)
			(layers "B.Cu" "B.Mask" "B.Paste")
			(net "P12V_STBY_VIN_U81")
		)
		(pad "2" smd rect
			(at 0 0.9652 90)
			(size 1.397 1.143)
			(layers "B.Cu" "B.Mask" "B.Paste")
			(net "GND")
		)
	)
	(footprint ""
		(layer "B.Cu")
		(at 45.300392 -144.335754 90)
		(property "Reference" "C56"
			(at 0 0 90)
			(layer "B.SilkS")
			(hide yes)
			(effects
				(font
					(size 1.27 1.27)
				)
				(justify mirror)
			)
		)
		(property "Value" "SC1U16V3KX-5GP"
			(at 0 -2.8194 90)
			(unlocked yes)
			(layer "B.Fab")
			(hide yes)
			(effects
				(font
					(size 1.016 1.016)
					(thickness 0.1524)
				)
				(justify mirror)
			)
		)
		(property "Device Type" "C603H36"
			(at 0 -4.3434 90)
			(unlocked yes)
			(layer "B.Fab")
			(hide yes)
			(effects
				(font
					(size 1.016 1.016)
					(thickness 0.1524)
				)
				(justify mirror)
			)
		)
		(duplicate_pad_numbers_are_jumpers no)
		(fp_line
			(start -0.508 0)
			(end 0.508 0)
			(stroke
				(width 0.2032)
				(type default)
			)
			(layer "B.SilkS")
		)
		(fp_rect
			(start 0.5842 1.3335)
			(end -0.5842 -1.3335)
			(stroke
				(width 0)
				(type default)
			)
			(fill no)
			(layer "B.CrtYd")
		)
		(fp_rect
			(start 0.5842 1.3335)
			(end -0.5842 -1.3335)
			(stroke
				(width 0)
				(type default)
			)
			(fill no)
			(layer "B.Fab")
		)
		(pad "1" smd custom
			(at 0 -0.762 270)
			(size 0.2159 0.2159)
			(layers "B.Cu" "B.Mask" "B.Paste")
			(net "P1V2_STBY")
			(options
				(clearance outline)
				(anchor circle)
			)
			(primitives
				(gr_poly
					(pts
						(arc
							(start -0.3302 0.4318)
							(mid -0.402042 0.402042)
							(end -0.4318 0.3302)
						)
						(arc
							(start -0.4318 -0.3302)
							(mid -0.402042 -0.402042)
							(end -0.3302 -0.4318)
						)
						(arc
							(start 0.3302 -0.4318)
							(mid 0.402042 -0.402042)
							(end 0.4318 -0.3302)
						)
						(arc
							(start 0.4318 0.3302)
							(mid 0.402042 0.402042)
							(end 0.3302 0.4318)
						)
					)
					(width 0)
					(fill yes)
				)
			)
		)
		(pad "2" smd custom
			(at 0 0.762 270)
			(size 0.2159 0.2159)
			(layers "B.Cu" "B.Mask" "B.Paste")
			(net "GND")
			(options
				(clearance outline)
				(anchor circle)
			)
			(primitives
				(gr_poly
					(pts
						(arc
							(start -0.3302 0.4318)
							(mid -0.402042 0.402042)
							(end -0.4318 0.3302)
						)
						(arc
							(start -0.4318 -0.3302)
							(mid -0.402042 -0.402042)
							(end -0.3302 -0.4318)
						)
						(arc
							(start 0.3302 -0.4318)
							(mid 0.402042 -0.402042)
							(end 0.4318 -0.3302)
						)
						(arc
							(start 0.4318 0.3302)
							(mid 0.402042 0.402042)
							(end 0.3302 0.4318)
						)
					)
					(width 0)
					(fill yes)
				)
			)
		)
	)
	(footprint ""
		(layer "B.Cu")
		(at 19.144742 -129.077466 180)
		(property "Reference" "R235"
			(at 0 0 0)
			(layer "B.SilkS")
			(hide yes)
			(effects
				(font
					(size 1.27 1.27)
				)
				(justify mirror)
			)
		)
		(property "Value" "120R2F-GP"
			(at -0.064008 -3.993896 180)
			(unlocked yes)
			(layer "B.Fab")
			(hide yes)
			(effects
				(font
					(size 1.016 1.016)
					(thickness 0.1524)
				)
				(justify mirror)
			)
		)
		(property "Device Type" "R402H16"
			(at -0.064008 -5.517896 180)
			(unlocked yes)
			(layer "B.Fab")
			(hide yes)
			(effects
				(font
					(size 1.016 1.016)
					(thickness 0.1524)
				)
				(justify mirror)
			)
		)
		(duplicate_pad_numbers_are_jumpers no)
		(fp_line
			(start 0.508 -0.9398)
			(end 0.508 0.9398)
			(stroke
				(width 0.1524)
				(type default)
			)
			(layer "B.SilkS")
		)
		(fp_line
			(start -0.508 -0.9398)
			(end 0.508 -0.9398)
			(stroke
				(width 0.1524)
				(type default)
			)
			(layer "B.SilkS")
		)
		(fp_rect
			(start 0.508 0.9398)
			(end -0.508 -0.9398)
			(stroke
				(width 0)
				(type default)
			)
			(fill no)
			(layer "B.CrtYd")
		)
		(fp_rect
			(start 0.508 0.9398)
			(end -0.508 -0.9398)
			(stroke
				(width 0)
				(type default)
			)
			(fill no)
			(layer "B.Fab")
		)
		(pad "1" smd custom
			(at 0 -0.4445)
			(size 0.1397 0.1397)
			(layers "B.Cu" "B.Mask" "B.Paste")
			(net "GND")
			(options
				(clearance outline)
				(anchor circle)
			)
			(primitives
				(gr_poly
					(pts
						(arc
							(start -0.1778 0.2794)
							(mid -0.249642 0.249642)
							(end -0.2794 0.1778)
						)
						(arc
							(start -0.2794 -0.1778)
							(mid -0.249642 -0.249642)
							(end -0.1778 -0.2794)
						)
						(arc
							(start 0.1778 -0.2794)
							(mid 0.249642 -0.249642)
							(end 0.2794 -0.1778)
						)
						(arc
							(start 0.2794 0.1778)
							(mid 0.249642 0.249642)
							(end 0.1778 0.2794)
						)
					)
					(width 0)
					(fill yes)
				)
			)
		)
		(pad "2" smd custom
			(at 0 0.4445)
			(size 0.1397 0.1397)
			(layers "B.Cu" "B.Mask" "B.Paste")
			(net "MEMA_1")
			(options
				(clearance outline)
				(anchor circle)
			)
			(primitives
				(gr_poly
					(pts
						(arc
							(start -0.1778 0.2794)
							(mid -0.249642 0.249642)
							(end -0.2794 0.1778)
						)
						(arc
							(start -0.2794 -0.1778)
							(mid -0.249642 -0.249642)
							(end -0.1778 -0.2794)
						)
						(arc
							(start 0.1778 -0.2794)
							(mid 0.249642 -0.249642)
							(end 0.2794 -0.1778)
						)
						(arc
							(start 0.2794 0.1778)
							(mid 0.249642 0.249642)
							(end 0.1778 0.2794)
						)
					)
					(width 0)
					(fill yes)
				)
			)
		)
	)
)
